(kicad_pcb
	(version 20260206)
	(generator "pcbnew")
	(generator_version "10.0")
	(general
		(thickness 1.6)
		(legacy_teardrops no)
	)
	(paper "A4")
	(title_block
		(title "04192023_DAF0TMB3IC0_F0TG_MB_C_brd_V02_OCP.brd")
		(comment 1 "Grand Teton / footprints 2177-2182 of 8354")
	)
	(layers
		(0 "F.Cu" signal "TOP")
		(4 "In1.Cu" signal "GND")
		(6 "In2.Cu" signal "IN1")
		(8 "In3.Cu" signal "GND1")
		(10 "In4.Cu" signal "IN2")
		(12 "In5.Cu" signal "GND2")
		(14 "In6.Cu" signal "IN3")
		(16 "In7.Cu" signal "GND3")
		(18 "In8.Cu" signal "VCC")
		(20 "In9.Cu" signal "VCC1")
		(22 "In10.Cu" signal "GND4")
		(24 "In11.Cu" signal "IN4")
		(26 "In12.Cu" signal "GND5")
		(28 "In13.Cu" signal "IN5")
		(30 "In14.Cu" signal "GND6")
		(32 "In15.Cu" signal "IN6")
		(34 "In16.Cu" signal "GND7")
		(2 "B.Cu" signal "BOTTOM")
		(9 "F.Adhes" user "F.Adhesive")
		(11 "B.Adhes" user "B.Adhesive")
		(13 "F.Paste" user "Package Geometry/Pastemask Top")
		(15 "B.Paste" user "Package Geometry/Pastemask Bottom")
		(5 "F.SilkS" user "Ref Des/Silkscreen Top")
		(7 "B.SilkS" user "Ref Des/Silkscreen Bottom")
		(1 "F.Mask" user "Board Geometry/Soldermask Top")
		(3 "B.Mask" user "Board Geometry/Soldermask Bottom")
		(17 "Dwgs.User" user "User.Drawings")
		(19 "Cmts.User" user "User.Comments")
		(21 "Eco1.User" user "User.Eco1")
		(23 "Eco2.User" user "User.Eco2")
		(25 "Edge.Cuts" user "Board Geometry/Outline")
		(27 "Margin" user)
		(31 "F.CrtYd" user "Package Geometry/Place Bound Top")
		(29 "B.CrtYd" user "Package Geometry/Place Bound Bottom")
		(35 "F.Fab" user "Ref Des/Assembly Top")
		(33 "B.Fab" user "Ref Des/Assembly Bottom")
	)
	(footprint ""
		(layer "F.Cu")
		(at 35.15868 -432.056794 180)
		(property "Reference" "R3110"
			(at 0 0 180)
			(layer "F.SilkS")
			(hide yes)
			(effects
				(font
					(size 1.27 1.27)
				)
			)
		)
		(property "Value" ""
			(at 0 0 180)
			(layer "F.Fab")
			(effects
				(font
					(size 1.27 1.27)
				)
			)
		)
		(duplicate_pad_numbers_are_jumpers no)
		(fp_line
			(start 0.7874 0.4064)
			(end -0.7874 0.4064)
			(stroke
				(width 0.1524)
				(type default)
			)
			(layer "F.SilkS")
		)
		(fp_line
			(start 0.7874 -0.4064)
			(end 0.7874 0.4064)
			(stroke
				(width 0.1524)
				(type default)
			)
			(layer "F.SilkS")
		)
		(fp_line
			(start -0.7874 0.4064)
			(end -0.7874 -0.4064)
			(stroke
				(width 0.1524)
				(type default)
			)
			(layer "F.SilkS")
		)
		(fp_line
			(start -0.7874 -0.4064)
			(end 0.7874 -0.4064)
			(stroke
				(width 0.1524)
				(type default)
			)
			(layer "F.SilkS")
		)
		(fp_line
			(start 0.67945 0.3048)
			(end 0.120396 0.3048)
			(stroke
				(width 0.1)
				(type default)
			)
			(layer "F.Fab")
		)
		(fp_line
			(start 0.67945 -0.3048)
			(end 0.67945 0.3048)
			(stroke
				(width 0.1)
				(type default)
			)
			(layer "F.Fab")
		)
		(fp_line
			(start 0.12065 -0.2794)
			(end 0.12065 -0.3048)
			(stroke
				(width 0.1)
				(type default)
			)
			(layer "F.Fab")
		)
		(fp_line
			(start 0.12065 -0.3048)
			(end 0.67945 -0.3048)
			(stroke
				(width 0.1)
				(type default)
			)
			(layer "F.Fab")
		)
		(fp_line
			(start 0.120396 0.3048)
			(end 0.120396 0.2794)
			(stroke
				(width 0.1)
				(type default)
			)
			(layer "F.Fab")
		)
		(fp_line
			(start 0.120396 0.2794)
			(end -0.12065 0.2794)
			(stroke
				(width 0.1)
				(type default)
			)
			(layer "F.Fab")
		)
		(fp_line
			(start -0.12065 0.3048)
			(end -0.67945 0.3048)
			(stroke
				(width 0.1)
				(type default)
			)
			(layer "F.Fab")
		)
		(fp_line
			(start -0.12065 0.2794)
			(end -0.12065 0.3048)
			(stroke
				(width 0.1)
				(type default)
			)
			(layer "F.Fab")
		)
		(fp_line
			(start -0.12065 -0.2794)
			(end 0.12065 -0.2794)
			(stroke
				(width 0.1)
				(type default)
			)
			(layer "F.Fab")
		)
		(fp_line
			(start -0.12065 -0.305054)
			(end -0.12065 -0.2794)
			(stroke
				(width 0.1)
				(type default)
			)
			(layer "F.Fab")
		)
		(fp_line
			(start -0.67945 0.3048)
			(end -0.67945 -0.305054)
			(stroke
				(width 0.1)
				(type default)
			)
			(layer "F.Fab")
		)
		(fp_line
			(start -0.67945 -0.305054)
			(end -0.12065 -0.305054)
			(stroke
				(width 0.1)
				(type default)
			)
			(layer "F.Fab")
		)
		(pad "1" smd circle
			(at -0.40005 0 180)
			(size 0 0)
			(layers "F.Cu" "F.Mask" "F.Paste")
			(net "SMB_1_BMC_GPU_SDA")
		)
		(pad "2" smd circle
			(at 0.40005 0 180)
			(size 0 0)
			(layers "F.Cu" "F.Mask" "F.Paste")
			(net "SMB_1_BMC_GPU_R_SDA")
		)
	)
	(footprint ""
		(layer "F.Cu")
		(at 215.956134 -34.508948 180)
		(property "Reference" "R3592"
			(at 0 0 180)
			(layer "F.SilkS")
			(hide yes)
			(effects
				(font
					(size 1.27 1.27)
				)
			)
		)
		(property "Value" ""
			(at 0 0 180)
			(layer "F.Fab")
			(effects
				(font
					(size 1.27 1.27)
				)
			)
		)
		(duplicate_pad_numbers_are_jumpers no)
		(fp_line
			(start 0.7874 0.4064)
			(end -0.7874 0.4064)
			(stroke
				(width 0.1524)
				(type default)
			)
			(layer "F.SilkS")
		)
		(fp_line
			(start 0.7874 -0.4064)
			(end 0.7874 0.4064)
			(stroke
				(width 0.1524)
				(type default)
			)
			(layer "F.SilkS")
		)
		(fp_line
			(start -0.7874 0.4064)
			(end -0.7874 -0.4064)
			(stroke
				(width 0.1524)
				(type default)
			)
			(layer "F.SilkS")
		)
		(fp_line
			(start -0.7874 -0.4064)
			(end 0.7874 -0.4064)
			(stroke
				(width 0.1524)
				(type default)
			)
			(layer "F.SilkS")
		)
		(fp_line
			(start 0.67945 0.3048)
			(end 0.120396 0.3048)
			(stroke
				(width 0.1)
				(type default)
			)
			(layer "F.Fab")
		)
		(fp_line
			(start 0.67945 -0.3048)
			(end 0.67945 0.3048)
			(stroke
				(width 0.1)
				(type default)
			)
			(layer "F.Fab")
		)
		(fp_line
			(start 0.12065 -0.2794)
			(end 0.12065 -0.3048)
			(stroke
				(width 0.1)
				(type default)
			)
			(layer "F.Fab")
		)
		(fp_line
			(start 0.12065 -0.3048)
			(end 0.67945 -0.3048)
			(stroke
				(width 0.1)
				(type default)
			)
			(layer "F.Fab")
		)
		(fp_line
			(start 0.120396 0.3048)
			(end 0.120396 0.2794)
			(stroke
				(width 0.1)
				(type default)
			)
			(layer "F.Fab")
		)
		(fp_line
			(start 0.120396 0.2794)
			(end -0.12065 0.2794)
			(stroke
				(width 0.1)
				(type default)
			)
			(layer "F.Fab")
		)
		(fp_line
			(start -0.12065 0.3048)
			(end -0.67945 0.3048)
			(stroke
				(width 0.1)
				(type default)
			)
			(layer "F.Fab")
		)
		(fp_line
			(start -0.12065 0.2794)
			(end -0.12065 0.3048)
			(stroke
				(width 0.1)
				(type default)
			)
			(layer "F.Fab")
		)
		(fp_line
			(start -0.12065 -0.2794)
			(end 0.12065 -0.2794)
			(stroke
				(width 0.1)
				(type default)
			)
			(layer "F.Fab")
		)
		(fp_line
			(start -0.12065 -0.305054)
			(end -0.12065 -0.2794)
			(stroke
				(width 0.1)
				(type default)
			)
			(layer "F.Fab")
		)
		(fp_line
			(start -0.67945 0.3048)
			(end -0.67945 -0.305054)
			(stroke
				(width 0.1)
				(type default)
			)
			(layer "F.Fab")
		)
		(fp_line
			(start -0.67945 -0.305054)
			(end -0.12065 -0.305054)
			(stroke
				(width 0.1)
				(type default)
			)
			(layer "F.Fab")
		)
		(pad "1" smd circle
			(at -0.40005 0 180)
			(size 0 0)
			(layers "F.Cu" "F.Mask" "F.Paste")
			(net "SMB_INA230_3V3AUX_SCL")
		)
		(pad "2" smd circle
			(at 0.40005 0 180)
			(size 0 0)
			(layers "F.Cu" "F.Mask" "F.Paste")
			(net "SMB_INA230_5_3V3AUX_SCL_R")
		)
	)
	(footprint ""
		(layer "F.Cu")
		(at 145.050002 -81.018888 -90)
		(property "Reference" "PR6006"
			(at 0 0 270)
			(layer "F.SilkS")
			(hide yes)
			(effects
				(font
					(size 1.27 1.27)
				)
			)
		)
		(property "Value" ""
			(at 0 0 270)
			(layer "F.Fab")
			(effects
				(font
					(size 1.27 1.27)
				)
			)
		)
		(duplicate_pad_numbers_are_jumpers no)
		(fp_line
			(start -0.7874 0.4064)
			(end -0.7874 -0.4064)
			(stroke
				(width 0.1524)
				(type default)
			)
			(layer "F.SilkS")
		)
		(fp_line
			(start 0.7874 0.4064)
			(end -0.7874 0.4064)
			(stroke
				(width 0.1524)
				(type default)
			)
			(layer "F.SilkS")
		)
		(fp_line
			(start -0.7874 -0.4064)
			(end 0.7874 -0.4064)
			(stroke
				(width 0.1524)
				(type default)
			)
			(layer "F.SilkS")
		)
		(fp_line
			(start 0.7874 -0.4064)
			(end 0.7874 0.4064)
			(stroke
				(width 0.1524)
				(type default)
			)
			(layer "F.SilkS")
		)
		(fp_line
			(start -0.67945 0.3048)
			(end -0.67945 -0.305054)
			(stroke
				(width 0.1)
				(type default)
			)
			(layer "F.Fab")
		)
		(fp_line
			(start -0.12065 0.3048)
			(end -0.67945 0.3048)
			(stroke
				(width 0.1)
				(type default)
			)
			(layer "F.Fab")
		)
		(fp_line
			(start 0.120396 0.3048)
			(end 0.120396 0.2794)
			(stroke
				(width 0.1)
				(type default)
			)
			(layer "F.Fab")
		)
		(fp_line
			(start 0.67945 0.3048)
			(end 0.120396 0.3048)
			(stroke
				(width 0.1)
				(type default)
			)
			(layer "F.Fab")
		)
		(fp_line
			(start -0.12065 0.2794)
			(end -0.12065 0.3048)
			(stroke
				(width 0.1)
				(type default)
			)
			(layer "F.Fab")
		)
		(fp_line
			(start 0.120396 0.2794)
			(end -0.12065 0.2794)
			(stroke
				(width 0.1)
				(type default)
			)
			(layer "F.Fab")
		)
		(fp_line
			(start -0.12065 -0.2794)
			(end 0.12065 -0.2794)
			(stroke
				(width 0.1)
				(type default)
			)
			(layer "F.Fab")
		)
		(fp_line
			(start 0.12065 -0.2794)
			(end 0.12065 -0.3048)
			(stroke
				(width 0.1)
				(type default)
			)
			(layer "F.Fab")
		)
		(fp_line
			(start 0.12065 -0.3048)
			(end 0.67945 -0.3048)
			(stroke
				(width 0.1)
				(type default)
			)
			(layer "F.Fab")
		)
		(fp_line
			(start 0.67945 -0.3048)
			(end 0.67945 0.3048)
			(stroke
				(width 0.1)
				(type default)
			)
			(layer "F.Fab")
		)
		(fp_line
			(start -0.67945 -0.305054)
			(end -0.12065 -0.305054)
			(stroke
				(width 0.1)
				(type default)
			)
			(layer "F.Fab")
		)
		(fp_line
			(start -0.12065 -0.305054)
			(end -0.12065 -0.2794)
			(stroke
				(width 0.1)
				(type default)
			)
			(layer "F.Fab")
		)
		(pad "1" smd circle
			(at -0.40005 0 270)
			(size 0 0)
			(layers "F.Cu" "F.Mask" "F.Paste")
			(net "GND")
		)
		(pad "2" smd circle
			(at 0.40005 0 270)
			(size 0 0)
			(layers "F.Cu" "F.Mask" "F.Paste")
			(net "P1V8_AUX_MODE")
		)
	)
	(footprint ""
		(layer "F.Cu")
		(at 162.57143 -76.13142)
		(property "Reference" "Q4"
			(at -1.4224 -1.768348 0)
			(unlocked yes)
			(layer "F.SilkS")
			(effects
				(font
					(size 0.7874 0.5842)
					(thickness 0.1524)
				)
				(justify left)
			)
		)
		(property "Value" ""
			(at 0 0 0)
			(layer "F.Fab")
			(effects
				(font
					(size 1.27 1.27)
				)
			)
		)
		(duplicate_pad_numbers_are_jumpers no)
		(fp_line
			(start -1.332738 -1.100074)
			(end -0.4826 -1.100074)
			(stroke
				(width 0.1524)
				(type default)
			)
			(layer "F.SilkS")
		)
		(fp_line
			(start -1.332738 1.100074)
			(end -1.332738 -1.100074)
			(stroke
				(width 0.1524)
				(type default)
			)
			(layer "F.SilkS")
		)
		(fp_line
			(start -0.4826 -1.100074)
			(end 0 -0.541274)
			(stroke
				(width 0.1524)
				(type default)
			)
			(layer "F.SilkS")
		)
		(fp_line
			(start 0 -0.541274)
			(end 0.4826 -1.100074)
			(stroke
				(width 0.1524)
				(type default)
			)
			(layer "F.SilkS")
		)
		(fp_line
			(start 0.4826 -1.100074)
			(end 1.332738 -1.100074)
			(stroke
				(width 0.1524)
				(type default)
			)
			(layer "F.SilkS")
		)
		(fp_line
			(start 1.332738 -1.100074)
			(end 1.332738 1.100074)
			(stroke
				(width 0.1524)
				(type default)
			)
			(layer "F.SilkS")
		)
		(fp_line
			(start 1.332738 1.100074)
			(end -1.332738 1.100074)
			(stroke
				(width 0.1524)
				(type default)
			)
			(layer "F.SilkS")
		)
		(fp_poly
			(pts
				(xy -1.489456 -1.189482) (xy -2.23393 -1.43764) (xy -1.737614 -1.933956)
			)
			(stroke
				(width 0)
				(type default)
			)
			(fill yes)
			(layer "F.SilkS")
		)
		(fp_line
			(start -0.674878 -1.100074)
			(end 0.674878 -1.100074)
			(stroke
				(width 0.1)
				(type default)
			)
			(layer "F.Fab")
		)
		(fp_line
			(start -0.674878 1.100074)
			(end -0.674878 -1.100074)
			(stroke
				(width 0.1)
				(type default)
			)
			(layer "F.Fab")
		)
		(fp_line
			(start 0.674878 -1.100074)
			(end 0.674878 1.100074)
			(stroke
				(width 0.1)
				(type default)
			)
			(layer "F.Fab")
		)
		(fp_line
			(start 0.674878 1.100074)
			(end -0.674878 1.100074)
			(stroke
				(width 0.1)
				(type default)
			)
			(layer "F.Fab")
		)
		(fp_poly
			(pts
				(xy -2.2352 -0.298958) (xy -2.2352 -1.001014) (xy -1.533144 -0.649986)
			)
			(stroke
				(width 0)
				(type default)
			)
			(fill yes)
			(layer "F.Fab")
		)
		(pad "1" smd rect
			(at -0.94996 -0.649986 90)
			(size 0.4318 0.508)
			(layers "F.Cu" "F.Mask" "F.Paste")
			(net "GND")
		)
		(pad "2" smd rect
			(at -0.94996 0 90)
			(size 0.4318 0.508)
			(layers "F.Cu" "F.Mask" "F.Paste")
			(net "IRQ_LVC3_WAKE_N")
		)
		(pad "3" smd rect
			(at -0.94996 0.649986 90)
			(size 0.4318 0.508)
			(layers "F.Cu" "F.Mask" "F.Paste")
			(net "IRQ_WAKE_R_N")
		)
		(pad "4" smd rect
			(at 0.94996 0.649986 90)
			(size 0.4318 0.508)
			(layers "F.Cu" "F.Mask" "F.Paste")
			(net "GND")
		)
		(pad "5" smd rect
			(at 0.94996 0 90)
			(size 0.4318 0.508)
			(layers "F.Cu" "F.Mask" "F.Paste")
			(net "IRQ_LVC3_WAKE")
		)
		(pad "6" smd rect
			(at 0.94996 -0.649986 90)
			(size 0.4318 0.508)
			(layers "F.Cu" "F.Mask" "F.Paste")
			(net "IRQ_LVC3_WAKE")
		)
	)
	(footprint ""
		(layer "F.Cu")
		(at 444.621666 -402.81987)
		(property "Reference" "PR6553"
			(at 0 0 0)
			(layer "F.SilkS")
			(hide yes)
			(effects
				(font
					(size 1.27 1.27)
				)
			)
		)
		(property "Value" ""
			(at 0 0 0)
			(layer "F.Fab")
			(effects
				(font
					(size 1.27 1.27)
				)
			)
		)
		(duplicate_pad_numbers_are_jumpers no)
		(fp_line
			(start -0.7874 -0.4064)
			(end 0.7874 -0.4064)
			(stroke
				(width 0.1524)
				(type default)
			)
			(layer "F.SilkS")
		)
		(fp_line
			(start -0.7874 0.4064)
			(end -0.7874 -0.4064)
			(stroke
				(width 0.1524)
				(type default)
			)
			(layer "F.SilkS")
		)
		(fp_line
			(start 0.7874 -0.4064)
			(end 0.7874 0.4064)
			(stroke
				(width 0.1524)
				(type default)
			)
			(layer "F.SilkS")
		)
		(fp_line
			(start 0.7874 0.4064)
			(end -0.7874 0.4064)
			(stroke
				(width 0.1524)
				(type default)
			)
			(layer "F.SilkS")
		)
		(fp_line
			(start -0.67945 -0.305054)
			(end -0.12065 -0.305054)
			(stroke
				(width 0.1)
				(type default)
			)
			(layer "F.Fab")
		)
		(fp_line
			(start -0.67945 0.3048)
			(end -0.67945 -0.305054)
			(stroke
				(width 0.1)
				(type default)
			)
			(layer "F.Fab")
		)
		(fp_line
			(start -0.12065 -0.305054)
			(end -0.12065 -0.2794)
			(stroke
				(width 0.1)
				(type default)
			)
			(layer "F.Fab")
		)
		(fp_line
			(start -0.12065 -0.2794)
			(end 0.12065 -0.2794)
			(stroke
				(width 0.1)
				(type default)
			)
			(layer "F.Fab")
		)
		(fp_line
			(start -0.12065 0.2794)
			(end -0.12065 0.3048)
			(stroke
				(width 0.1)
				(type default)
			)
			(layer "F.Fab")
		)
		(fp_line
			(start -0.12065 0.3048)
			(end -0.67945 0.3048)
			(stroke
				(width 0.1)
				(type default)
			)
			(layer "F.Fab")
		)
		(fp_line
			(start 0.120396 0.2794)
			(end -0.12065 0.2794)
			(stroke
				(width 0.1)
				(type default)
			)
			(layer "F.Fab")
		)
		(fp_line
			(start 0.120396 0.3048)
			(end 0.120396 0.2794)
			(stroke
				(width 0.1)
				(type default)
			)
			(layer "F.Fab")
		)
		(fp_line
			(start 0.12065 -0.3048)
			(end 0.67945 -0.3048)
			(stroke
				(width 0.1)
				(type default)
			)
			(layer "F.Fab")
		)
		(fp_line
			(start 0.12065 -0.2794)
			(end 0.12065 -0.3048)
			(stroke
				(width 0.1)
				(type default)
			)
			(layer "F.Fab")
		)
		(fp_line
			(start 0.67945 -0.3048)
			(end 0.67945 0.3048)
			(stroke
				(width 0.1)
				(type default)
			)
			(layer "F.Fab")
		)
		(fp_line
			(start 0.67945 0.3048)
			(end 0.120396 0.3048)
			(stroke
				(width 0.1)
				(type default)
			)
			(layer "F.Fab")
		)
		(pad "1" smd circle
			(at -0.40005 0)
			(size 0 0)
			(layers "F.Cu" "F.Mask" "F.Paste")
			(net "P0V9_RETIMER_CPU0_LSET1")
		)
		(pad "2" smd circle
			(at 0.40005 0)
			(size 0 0)
			(layers "F.Cu" "F.Mask" "F.Paste")
			(net "GND")
		)
	)
	(footprint ""
		(layer "F.Cu")
		(at 36.319968 -133.857238)
		(property "Reference" "R4514"
			(at 0 0 0)
			(layer "F.SilkS")
			(hide yes)
			(effects
				(font
					(size 1.27 1.27)
				)
			)
		)
		(property "Value" ""
			(at 0 0 0)
			(layer "F.Fab")
			(effects
				(font
					(size 1.27 1.27)
				)
			)
		)
		(duplicate_pad_numbers_are_jumpers no)
		(fp_line
			(start -0.7874 -0.4064)
			(end 0.7874 -0.4064)
			(stroke
				(width 0.1524)
				(type default)
			)
			(layer "F.SilkS")
		)
		(fp_line
			(start -0.7874 0.4064)
			(end -0.7874 -0.4064)
			(stroke
				(width 0.1524)
				(type default)
			)
			(layer "F.SilkS")
		)
		(fp_line
			(start 0.7874 -0.4064)
			(end 0.7874 0.4064)
			(stroke
				(width 0.1524)
				(type default)
			)
			(layer "F.SilkS")
		)
		(fp_line
			(start 0.7874 0.4064)
			(end -0.7874 0.4064)
			(stroke
				(width 0.1524)
				(type default)
			)
			(layer "F.SilkS")
		)
		(fp_line
			(start -0.67945 -0.305054)
			(end -0.12065 -0.305054)
			(stroke
				(width 0.1)
				(type default)
			)
			(layer "F.Fab")
		)
		(fp_line
			(start -0.67945 0.3048)
			(end -0.67945 -0.305054)
			(stroke
				(width 0.1)
				(type default)
			)
			(layer "F.Fab")
		)
		(fp_line
			(start -0.12065 -0.305054)
			(end -0.12065 -0.2794)
			(stroke
				(width 0.1)
				(type default)
			)
			(layer "F.Fab")
		)
		(fp_line
			(start -0.12065 -0.2794)
			(end 0.12065 -0.2794)
			(stroke
				(width 0.1)
				(type default)
			)
			(layer "F.Fab")
		)
		(fp_line
			(start -0.12065 0.2794)
			(end -0.12065 0.3048)
			(stroke
				(width 0.1)
				(type default)
			)
			(layer "F.Fab")
		)
		(fp_line
			(start -0.12065 0.3048)
			(end -0.67945 0.3048)
			(stroke
				(width 0.1)
				(type default)
			)
			(layer "F.Fab")
		)
		(fp_line
			(start 0.120396 0.2794)
			(end -0.12065 0.2794)
			(stroke
				(width 0.1)
				(type default)
			)
			(layer "F.Fab")
		)
		(fp_line
			(start 0.120396 0.3048)
			(end 0.120396 0.2794)
			(stroke
				(width 0.1)
				(type default)
			)
			(layer "F.Fab")
		)
		(fp_line
			(start 0.12065 -0.3048)
			(end 0.67945 -0.3048)
			(stroke
				(width 0.1)
				(type default)
			)
			(layer "F.Fab")
		)
		(fp_line
			(start 0.12065 -0.2794)
			(end 0.12065 -0.3048)
			(stroke
				(width 0.1)
				(type default)
			)
			(layer "F.Fab")
		)
		(fp_line
			(start 0.67945 -0.3048)
			(end 0.67945 0.3048)
			(stroke
				(width 0.1)
				(type default)
			)
			(layer "F.Fab")
		)
		(fp_line
			(start 0.67945 0.3048)
			(end 0.120396 0.3048)
			(stroke
				(width 0.1)
				(type default)
			)
			(layer "F.Fab")
		)
		(pad "1" smd circle
			(at -0.40005 0)
			(size 0 0)
			(layers "F.Cu" "F.Mask" "F.Paste")
			(net "CLK_GEN2_GPU_FPGA_OE_R2_N")
		)
		(pad "2" smd circle
			(at 0.40005 0)
			(size 0 0)
			(layers "F.Cu" "F.Mask" "F.Paste")
			(net "GND")
		)
	)
)
